# Barreleye-G2_Tri-mode Expander-DVT-X01-SKU-BOM-X07-20171222_Final.xls.xlsx — Summary (bom)
| PLATFORM SOURCING AND PSL COMPLIANCE |  |  |  |  |  |  |  |  |  |
| Platform Name: |  |  |  |  |  |  |  |  |  |
| REVISION HISTORY |  |  |  |  |  |  |  |  |  |
| BOM Revision: | ECR # | Revision Description | Originator | Date |  |  |  |  |  |
| X03 |  | EVT |  | 42888 |  |  |  |  |  |
| X07 |  |  |  | 43091 |  |  |  |  |  |
| Commodity Sourcing | # of components (X00 BOM) | % of Total | # of components (X01 BOM) | % of Total | # of components (X02 BOM) | % of Total | # of components (RTS) | % of Total | Risk Mitigation Plans in Place |
| Sole Source |  |  |  |  |  |  |  |  |  |
| Single Source |  |  | 25 | 0.1404494382 |  |  |  |  |  |
| Multiple |  |  | 153 | 0.8595505618 |  |  |  |  | NA |
| Total |  |  | 178 | 1 |  |  |  |  | NA |
|  |  | # of components | # of components aligned with Customer PSL* | % PSL alignment |  |  |  |  |  |
| Class 1 (Customer Managed) |  |  |  |  |  |  |  |  |  |
| Class 2 (ODM Managed to Customer PSL) |  |  |  |  |  |  |  |  |  |
| All other components(ODM Managed to ODM PSL) |  |  |  |  |  |  |  |  |  |
| *RFQ and/or Contract will list requirements for complying with Customer's PSL |  |  |  |  |  |  |  |  |  |
| Reference for quotation |  |  |  |  |  |  |  |  |  |
